# T6G (Grand Teton) — schematic netlist excerpt (pin names and nets, part order shuffled) for the footprints in the layout excerpt that follows; sources: Cadence DE-HDL packaged netlist, KiCad conversion of 04192023_DAF0TMB3IC0_F0TG_MB_C_brd_V02_OCP.brd

C2046  Q_CAP  0.1UF 25V 10% X7R  pkg 0402  page 257 : A = P12V_AUX_ADC_TIC ; B = GND
R8465  Q_RES  10K 5% CHIP  pkg 0402LF  page 209 : A = P3V3_AUX ; B = PWRGD_PVDD18_S5_P0

(kicad_pcb
	(version 20260206)
	(generator "pcbnew")
	(generator_version "10.0")
	(general
		(thickness 1.6)
		(legacy_teardrops no)
	)
	(paper "A4")
	(title_block
		(title "04192023_DAF0TMB3IC0_F0TG_MB_C_brd_V02_OCP.brd")
		(comment 1 "Grand Teton / footprints 919-920 of 8354")
	)
	(layers
		(0 "F.Cu" signal "TOP")
		(4 "In1.Cu" signal "GND")
		(6 "In2.Cu" signal "IN1")
		(8 "In3.Cu" signal "GND1")
		(10 "In4.Cu" signal "IN2")
		(12 "In5.Cu" signal "GND2")
		(14 "In6.Cu" signal "IN3")
		(16 "In7.Cu" signal "GND3")
		(18 "In8.Cu" signal "VCC")
		(20 "In9.Cu" signal "VCC1")
		(22 "In10.Cu" signal "GND4")
		(24 "In11.Cu" signal "IN4")
		(26 "In12.Cu" signal "GND5")
		(28 "In13.Cu" signal "IN5")
		(30 "In14.Cu" signal "GND6")
		(32 "In15.Cu" signal "IN6")
		(34 "In16.Cu" signal "GND7")
		(2 "B.Cu" signal "BOTTOM")
		(9 "F.Adhes" user "F.Adhesive")
		(11 "B.Adhes" user "B.Adhesive")
		(13 "F.Paste" user "Package Geometry/Pastemask Top")
		(15 "B.Paste" user "Package Geometry/Pastemask Bottom")
		(5 "F.SilkS" user "Ref Des/Silkscreen Top")
		(7 "B.SilkS" user "Ref Des/Silkscreen Bottom")
		(1 "F.Mask" user "Board Geometry/Soldermask Top")
		(3 "B.Mask" user "Board Geometry/Soldermask Bottom")
		(17 "Dwgs.User" user "User.Drawings")
		(19 "Cmts.User" user "User.Comments")
		(21 "Eco1.User" user "User.Eco1")
		(23 "Eco2.User" user "User.Eco2")
		(25 "Edge.Cuts" user "Board Geometry/Outline")
		(27 "Margin" user)
		(31 "F.CrtYd" user "Package Geometry/Place Bound Top")
		(29 "B.CrtYd" user "Package Geometry/Place Bound Bottom")
		(35 "F.Fab" user "Ref Des/Assembly Top")
		(33 "B.Fab" user "Ref Des/Assembly Bottom")
	)
	(footprint ""
		(layer "F.Cu")
		(at 331.633068 -136.473946)
		(property "Reference" "R8465"
			(at 0 0 0)
			(layer "F.SilkS")
			(hide yes)
			(effects
				(font
					(size 1.27 1.27)
				)
			)
		)
		(property "Value" ""
			(at 0 0 0)
			(layer "F.Fab")
			(effects
				(font
					(size 1.27 1.27)
				)
			)
		)
		(duplicate_pad_numbers_are_jumpers no)
		(fp_line
			(start -0.7874 -0.4064)
			(end 0.7874 -0.4064)
			(stroke
				(width 0.1524)
				(type default)
			)
			(layer "F.SilkS")
		)
		(fp_line
			(start -0.7874 0.4064)
			(end -0.7874 -0.4064)
			(stroke
				(width 0.1524)
				(type default)
			)
			(layer "F.SilkS")
		)
		(fp_line
			(start 0.7874 -0.4064)
			(end 0.7874 0.4064)
			(stroke
				(width 0.1524)
				(type default)
			)
			(layer "F.SilkS")
		)
		(fp_line
			(start 0.7874 0.4064)
			(end -0.7874 0.4064)
			(stroke
				(width 0.1524)
				(type default)
			)
			(layer "F.SilkS")
		)
		(fp_line
			(start -0.67945 -0.305054)
			(end -0.12065 -0.305054)
			(stroke
				(width 0.1)
				(type default)
			)
			(layer "F.Fab")
		)
		(fp_line
			(start -0.67945 0.3048)
			(end -0.67945 -0.305054)
			(stroke
				(width 0.1)
				(type default)
			)
			(layer "F.Fab")
		)
		(fp_line
			(start -0.12065 -0.305054)
			(end -0.12065 -0.2794)
			(stroke
				(width 0.1)
				(type default)
			)
			(layer "F.Fab")
		)
		(fp_line
			(start -0.12065 -0.2794)
			(end 0.12065 -0.2794)
			(stroke
				(width 0.1)
				(type default)
			)
			(layer "F.Fab")
		)
		(fp_line
			(start -0.12065 0.2794)
			(end -0.12065 0.3048)
			(stroke
				(width 0.1)
				(type default)
			)
			(layer "F.Fab")
		)
		(fp_line
			(start -0.12065 0.3048)
			(end -0.67945 0.3048)
			(stroke
				(width 0.1)
				(type default)
			)
			(layer "F.Fab")
		)
		(fp_line
			(start 0.120396 0.2794)
			(end -0.12065 0.2794)
			(stroke
				(width 0.1)
				(type default)
			)
			(layer "F.Fab")
		)
		(fp_line
			(start 0.120396 0.3048)
			(end 0.120396 0.2794)
			(stroke
				(width 0.1)
				(type default)
			)
			(layer "F.Fab")
		)
		(fp_line
			(start 0.12065 -0.3048)
			(end 0.67945 -0.3048)
			(stroke
				(width 0.1)
				(type default)
			)
			(layer "F.Fab")
		)
		(fp_line
			(start 0.12065 -0.2794)
			(end 0.12065 -0.3048)
			(stroke
				(width 0.1)
				(type default)
			)
			(layer "F.Fab")
		)
		(fp_line
			(start 0.67945 -0.3048)
			(end 0.67945 0.3048)
			(stroke
				(width 0.1)
				(type default)
			)
			(layer "F.Fab")
		)
		(fp_line
			(start 0.67945 0.3048)
			(end 0.120396 0.3048)
			(stroke
				(width 0.1)
				(type default)
			)
			(layer "F.Fab")
		)
		(pad "1" smd circle
			(at -0.40005 0)
			(size 0 0)
			(layers "F.Cu" "F.Mask" "F.Paste")
			(net "P3V3_AUX")
		)
		(pad "2" smd circle
			(at 0.40005 0)
			(size 0 0)
			(layers "F.Cu" "F.Mask" "F.Paste")
			(net "PWRGD_PVDD18_S5_P0")
		)
	)
	(footprint ""
		(layer "F.Cu")
		(at 319.940178 -47.002954)
		(property "Reference" "C2046"
			(at 0 0 0)
			(layer "F.SilkS")
			(hide yes)
			(effects
				(font
					(size 1.27 1.27)
				)
			)
		)
		(property "Value" ""
			(at 0 0 0)
			(layer "F.Fab")
			(effects
				(font
					(size 1.27 1.27)
				)
			)
		)
		(duplicate_pad_numbers_are_jumpers no)
		(fp_line
			(start -0.7874 -0.4064)
			(end 0.7874 -0.4064)
			(stroke
				(width 0.1524)
				(type default)
			)
			(layer "F.SilkS")
		)
		(fp_line
			(start -0.7874 0.4064)
			(end -0.7874 -0.4064)
			(stroke
				(width 0.1524)
				(type default)
			)
			(layer "F.SilkS")
		)
		(fp_line
			(start 0.7874 -0.4064)
			(end 0.7874 0.4064)
			(stroke
				(width 0.1524)
				(type default)
			)
			(layer "F.SilkS")
		)
		(fp_line
			(start 0.7874 0.4064)
			(end -0.7874 0.4064)
			(stroke
				(width 0.1524)
				(type default)
			)
			(layer "F.SilkS")
		)
		(fp_line
			(start -0.67945 -0.305054)
			(end -0.12065 -0.305054)
			(stroke
				(width 0.1)
				(type default)
			)
			(layer "F.Fab")
		)
		(fp_line
			(start -0.67945 0.3048)
			(end -0.67945 -0.305054)
			(stroke
				(width 0.1)
				(type default)
			)
			(layer "F.Fab")
		)
		(fp_line
			(start -0.12065 -0.305054)
			(end -0.12065 -0.2794)
			(stroke
				(width 0.1)
				(type default)
			)
			(layer "F.Fab")
		)
		(fp_line
			(start -0.12065 -0.2794)
			(end 0.12065 -0.2794)
			(stroke
				(width 0.1)
				(type default)
			)
			(layer "F.Fab")
		)
		(fp_line
			(start -0.12065 0.2794)
			(end -0.12065 0.3048)
			(stroke
				(width 0.1)
				(type default)
			)
			(layer "F.Fab")
		)
		(fp_line
			(start -0.12065 0.3048)
			(end -0.67945 0.3048)
			(stroke
				(width 0.1)
				(type default)
			)
			(layer "F.Fab")
		)
		(fp_line
			(start 0.120396 0.2794)
			(end -0.12065 0.2794)
			(stroke
				(width 0.1)
				(type default)
			)
			(layer "F.Fab")
		)
		(fp_line
			(start 0.120396 0.3048)
			(end 0.120396 0.2794)
			(stroke
				(width 0.1)
				(type default)
			)
			(layer "F.Fab")
		)
		(fp_line
			(start 0.12065 -0.3048)
			(end 0.67945 -0.3048)
			(stroke
				(width 0.1)
				(type default)
			)
			(layer "F.Fab")
		)
		(fp_line
			(start 0.12065 -0.2794)
			(end 0.12065 -0.3048)
			(stroke
				(width 0.1)
				(type default)
			)
			(layer "F.Fab")
		)
		(fp_line
			(start 0.67945 -0.3048)
			(end 0.67945 0.3048)
			(stroke
				(width 0.1)
				(type default)
			)
			(layer "F.Fab")
		)
		(fp_line
			(start 0.67945 0.3048)
			(end 0.120396 0.3048)
			(stroke
				(width 0.1)
				(type default)
			)
			(layer "F.Fab")
		)
		(pad "1" smd circle
			(at -0.40005 0)
			(size 0 0)
			(layers "F.Cu" "F.Mask" "F.Paste")
			(net "P12V_AUX_ADC_TIC")
		)
		(pad "2" smd circle
			(at 0.40005 0)
			(size 0 0)
			(layers "F.Cu" "F.Mask" "F.Paste")
			(net "GND")
		)
	)
)
